(kicad_pcb
	(version 20260206)
	(generator "pcbnew")
	(generator_version "10.0")
	(general
		(thickness 1.6)
		(legacy_teardrops no)
	)
	(paper "A4")
	(title_block
		(title "Bryce Canyon_R.DPB_16317-1_OCP.brd")
		(comment 1 "Bryce Canyon / footprints 860-867 of 2099")
	)
	(layers
		(0 "F.Cu" signal "TOP")
		(4 "In1.Cu" signal "L2GND")
		(6 "In2.Cu" signal "L3")
		(8 "In3.Cu" signal "L4VCC")
		(10 "In4.Cu" signal "L5VCC")
		(12 "In5.Cu" signal "L6")
		(14 "In6.Cu" signal "L7GND")
		(2 "B.Cu" signal "BOTTOM")
		(9 "F.Adhes" user "F.Adhesive")
		(11 "B.Adhes" user "B.Adhesive")
		(13 "F.Paste" user "Package Geometry/Pastemask Top")
		(15 "B.Paste" user "Package Geometry/Pastemask Bottom")
		(5 "F.SilkS" user "Ref Des/Silkscreen Top")
		(7 "B.SilkS" user "Ref Des/Silkscreen Bottom")
		(1 "F.Mask" user "Board Geometry/Soldermask Top")
		(3 "B.Mask" user "Board Geometry/Soldermask Bottom")
		(17 "Dwgs.User" user "User.Drawings")
		(19 "Cmts.User" user "User.Comments")
		(21 "Eco1.User" user "User.Eco1")
		(23 "Eco2.User" user "User.Eco2")
		(25 "Edge.Cuts" user "Board Geometry/Outline")
		(27 "Margin" user)
		(31 "F.CrtYd" user "Package Geometry/Place Bound Top")
		(29 "B.CrtYd" user "Package Geometry/Place Bound Bottom")
		(35 "F.Fab" user "Ref Des/Assembly Top")
		(33 "B.Fab" user "Ref Des/Assembly Bottom")
	)
	(footprint ""
		(layer "F.Cu")
		(at 321.634612 -14.660626 -90)
		(property "Reference" "C419"
			(at 0 0 270)
			(layer "F.SilkS")
			(hide yes)
			(effects
				(font
					(size 1.27 1.27)
				)
			)
		)
		(property "Value" "SCD01U16V1KX-GP"
			(at -2.8321 -1.7399 270)
			(unlocked yes)
			(layer "F.Fab")
			(hide yes)
			(effects
				(font
					(size 1.016 1.016)
					(thickness 0.1524)
				)
			)
		)
		(property "Device Type" "C0201H13"
			(at -2.8321 -3.2639 270)
			(unlocked yes)
			(layer "F.Fab")
			(hide yes)
			(effects
				(font
					(size 1.016 1.016)
					(thickness 0.1524)
				)
			)
		)
		(duplicate_pad_numbers_are_jumpers no)
		(fp_rect
			(start -0.2794 0.6477)
			(end 0.2794 -0.6477)
			(stroke
				(width 0)
				(type default)
			)
			(fill no)
			(layer "F.CrtYd")
		)
		(fp_rect
			(start -0.2794 0.6477)
			(end 0.2794 -0.6477)
			(stroke
				(width 0)
				(type default)
			)
			(fill no)
			(layer "F.Fab")
		)
		(pad "1" smd custom
			(at 0 -0.2794 270)
			(size 0.0762 0.0762)
			(layers "F.Cu" "F.Mask" "F.Paste")
			(net "SAS_HDD_RX_P30")
			(options
				(clearance outline)
				(anchor circle)
			)
			(primitives
				(gr_poly
					(pts
						(arc
							(start 0.1524 -0.127)
							(mid 0.137521 -0.162921)
							(end 0.1016 -0.1778)
						)
						(arc
							(start -0.1016 -0.1778)
							(mid -0.137521 -0.162921)
							(end -0.1524 -0.127)
						)
						(arc
							(start -0.1524 0.127)
							(mid -0.137521 0.162921)
							(end -0.1016 0.1778)
						)
						(arc
							(start 0.1016 0.1778)
							(mid 0.137521 0.162921)
							(end 0.1524 0.127)
						)
					)
					(width 0)
					(fill yes)
				)
			)
		)
		(pad "2" smd custom
			(at 0 0.2794 270)
			(size 0.0762 0.0762)
			(layers "F.Cu" "F.Mask" "F.Paste")
			(net "PHY_SCC_B_TO_DRV_B_30_DP")
			(options
				(clearance outline)
				(anchor circle)
			)
			(primitives
				(gr_poly
					(pts
						(arc
							(start 0.1524 -0.127)
							(mid 0.137521 -0.162921)
							(end 0.1016 -0.1778)
						)
						(arc
							(start -0.1016 -0.1778)
							(mid -0.137521 -0.162921)
							(end -0.1524 -0.127)
						)
						(arc
							(start -0.1524 0.127)
							(mid -0.137521 0.162921)
							(end -0.1016 0.1778)
						)
						(arc
							(start 0.1016 0.1778)
							(mid 0.137521 0.162921)
							(end 0.1524 0.127)
						)
					)
					(width 0)
					(fill yes)
				)
			)
		)
	)
	(footprint ""
		(layer "F.Cu")
		(at 433.324 -143.891 90)
		(property "Reference" "C312"
			(at 0 0 90)
			(layer "F.SilkS")
			(hide yes)
			(effects
				(font
					(size 1.27 1.27)
				)
			)
		)
		(property "Value" "SCD033U25V2KX-GP"
			(at 1.1811 -2.7051 90)
			(unlocked yes)
			(layer "F.Fab")
			(hide yes)
			(effects
				(font
					(size 1.016 1.016)
					(thickness 0.1524)
				)
			)
		)
		(property "Device Type" "C402H22"
			(at 1.1811 -4.2291 90)
			(unlocked yes)
			(layer "F.Fab")
			(hide yes)
			(effects
				(font
					(size 1.016 1.016)
					(thickness 0.1524)
				)
			)
		)
		(duplicate_pad_numbers_are_jumpers no)
		(fp_rect
			(start -0.4318 0.9525)
			(end 0.4318 -0.9525)
			(stroke
				(width 0)
				(type default)
			)
			(fill no)
			(layer "F.CrtYd")
		)
		(fp_rect
			(start -0.4318 0.9525)
			(end 0.4318 -0.9525)
			(stroke
				(width 0)
				(type default)
			)
			(fill no)
			(layer "F.Fab")
		)
		(pad "1" smd custom
			(at 0 -0.4445 90)
			(size 0.1524 0.1524)
			(layers "F.Cu" "F.Mask" "F.Paste")
			(net "P12V_B")
			(options
				(clearance outline)
				(anchor circle)
			)
			(primitives
				(gr_poly
					(pts
						(arc
							(start 0.3048 -0.2032)
							(mid 0.275042 -0.275042)
							(end 0.2032 -0.3048)
						)
						(arc
							(start -0.2032 -0.3048)
							(mid -0.275042 -0.275042)
							(end -0.3048 -0.2032)
						)
						(arc
							(start -0.3048 0.2032)
							(mid -0.275042 0.275042)
							(end -0.2032 0.3048)
						)
						(arc
							(start 0.2032 0.3048)
							(mid 0.275042 0.275042)
							(end 0.3048 0.2032)
						)
					)
					(width 0)
					(fill yes)
				)
			)
		)
		(pad "2" smd custom
			(at 0 0.4445 90)
			(size 0.1524 0.1524)
			(layers "F.Cu" "F.Mask" "F.Paste")
			(net "SW_HDD_N21")
			(options
				(clearance outline)
				(anchor circle)
			)
			(primitives
				(gr_poly
					(pts
						(arc
							(start 0.3048 -0.2032)
							(mid 0.275042 -0.275042)
							(end 0.2032 -0.3048)
						)
						(arc
							(start -0.2032 -0.3048)
							(mid -0.275042 -0.275042)
							(end -0.3048 -0.2032)
						)
						(arc
							(start -0.3048 0.2032)
							(mid -0.275042 0.275042)
							(end -0.2032 0.3048)
						)
						(arc
							(start 0.2032 0.3048)
							(mid 0.275042 0.275042)
							(end 0.3048 0.2032)
						)
					)
					(width 0)
					(fill yes)
				)
			)
		)
	)
	(footprint ""
		(layer "F.Cu")
		(at 105.915968 -212.312504 -90)
		(property "Reference" "R197"
			(at 0 0 270)
			(layer "F.SilkS")
			(hide yes)
			(effects
				(font
					(size 1.27 1.27)
				)
			)
		)
		(property "Value" "4K7R2F-GP"
			(at 0.064008 -3.993896 270)
			(unlocked yes)
			(layer "F.Fab")
			(hide yes)
			(effects
				(font
					(size 1.016 1.016)
					(thickness 0.1524)
				)
			)
		)
		(property "Device Type" "R402H16"
			(at 0.064008 -5.517896 270)
			(unlocked yes)
			(layer "F.Fab")
			(hide yes)
			(effects
				(font
					(size 1.016 1.016)
					(thickness 0.1524)
				)
			)
		)
		(duplicate_pad_numbers_are_jumpers no)
		(fp_line
			(start -0.508 -0.9398)
			(end -0.508 0.9398)
			(stroke
				(width 0.1524)
				(type default)
			)
			(layer "F.SilkS")
		)
		(fp_line
			(start 0.508 -0.9398)
			(end -0.508 -0.9398)
			(stroke
				(width 0.1524)
				(type default)
			)
			(layer "F.SilkS")
		)
		(fp_rect
			(start -0.508 0.9398)
			(end 0.508 -0.9398)
			(stroke
				(width 0)
				(type default)
			)
			(fill no)
			(layer "F.CrtYd")
		)
		(fp_rect
			(start -0.508 0.9398)
			(end 0.508 -0.9398)
			(stroke
				(width 0)
				(type default)
			)
			(fill no)
			(layer "F.Fab")
		)
		(pad "1" smd custom
			(at 0 -0.4445 270)
			(size 0.1397 0.1397)
			(layers "F.Cu" "F.Mask" "F.Paste")
			(net "DRIVE_B_3_ACT")
			(options
				(clearance outline)
				(anchor circle)
			)
			(primitives
				(gr_poly
					(pts
						(arc
							(start -0.1778 -0.2794)
							(mid -0.249642 -0.249642)
							(end -0.2794 -0.1778)
						)
						(arc
							(start -0.2794 0.1778)
							(mid -0.249642 0.249642)
							(end -0.1778 0.2794)
						)
						(arc
							(start 0.1778 0.2794)
							(mid 0.249642 0.249642)
							(end 0.2794 0.1778)
						)
						(arc
							(start 0.2794 -0.1778)
							(mid 0.249642 -0.249642)
							(end 0.1778 -0.2794)
						)
					)
					(width 0)
					(fill yes)
				)
			)
		)
		(pad "2" smd custom
			(at 0 0.4445 270)
			(size 0.1397 0.1397)
			(layers "F.Cu" "F.Mask" "F.Paste")
			(net "GND")
			(options
				(clearance outline)
				(anchor circle)
			)
			(primitives
				(gr_poly
					(pts
						(arc
							(start -0.1778 -0.2794)
							(mid -0.249642 -0.249642)
							(end -0.2794 -0.1778)
						)
						(arc
							(start -0.2794 0.1778)
							(mid -0.249642 0.249642)
							(end -0.1778 0.2794)
						)
						(arc
							(start 0.1778 0.2794)
							(mid 0.249642 0.249642)
							(end 0.2794 0.1778)
						)
						(arc
							(start 0.2794 -0.1778)
							(mid 0.249642 -0.249642)
							(end 0.1778 -0.2794)
						)
					)
					(width 0)
					(fill yes)
				)
			)
		)
	)
	(footprint ""
		(layer "F.Cu")
		(at 146.431 -263.779 -90)
		(property "Reference" "C82"
			(at 0 0 270)
			(layer "F.SilkS")
			(hide yes)
			(effects
				(font
					(size 1.27 1.27)
				)
			)
		)
		(property "Value" "SC1U16V3KX-5GP"
			(at 0 -2.8194 270)
			(unlocked yes)
			(layer "F.Fab")
			(hide yes)
			(effects
				(font
					(size 1.016 1.016)
					(thickness 0.1524)
				)
			)
		)
		(property "Device Type" "C603H36"
			(at 0 -4.3434 270)
			(unlocked yes)
			(layer "F.Fab")
			(hide yes)
			(effects
				(font
					(size 1.016 1.016)
					(thickness 0.1524)
				)
			)
		)
		(duplicate_pad_numbers_are_jumpers no)
		(fp_line
			(start 0.508 0)
			(end -0.508 0)
			(stroke
				(width 0.2032)
				(type default)
			)
			(layer "F.SilkS")
		)
		(fp_rect
			(start -0.5842 1.3335)
			(end 0.5842 -1.3335)
			(stroke
				(width 0)
				(type default)
			)
			(fill no)
			(layer "F.CrtYd")
		)
		(fp_rect
			(start -0.5842 1.3335)
			(end 0.5842 -1.3335)
			(stroke
				(width 0)
				(type default)
			)
			(fill no)
			(layer "F.Fab")
		)
		(pad "1" smd custom
			(at 0 -0.762 270)
			(size 0.2159 0.2159)
			(layers "F.Cu" "F.Mask" "F.Paste")
			(net "P5V_HDD4")
			(options
				(clearance outline)
				(anchor circle)
			)
			(primitives
				(gr_poly
					(pts
						(arc
							(start -0.3302 -0.4318)
							(mid -0.402042 -0.402042)
							(end -0.4318 -0.3302)
						)
						(arc
							(start -0.4318 0.3302)
							(mid -0.402042 0.402042)
							(end -0.3302 0.4318)
						)
						(arc
							(start 0.3302 0.4318)
							(mid 0.402042 0.402042)
							(end 0.4318 0.3302)
						)
						(arc
							(start 0.4318 -0.3302)
							(mid 0.402042 -0.402042)
							(end 0.3302 -0.4318)
						)
					)
					(width 0)
					(fill yes)
				)
			)
		)
		(pad "2" smd custom
			(at 0 0.762 270)
			(size 0.2159 0.2159)
			(layers "F.Cu" "F.Mask" "F.Paste")
			(net "GND")
			(options
				(clearance outline)
				(anchor circle)
			)
			(primitives
				(gr_poly
					(pts
						(arc
							(start -0.3302 -0.4318)
							(mid -0.402042 -0.402042)
							(end -0.4318 -0.3302)
						)
						(arc
							(start -0.4318 0.3302)
							(mid -0.402042 0.402042)
							(end -0.3302 0.4318)
						)
						(arc
							(start 0.3302 0.4318)
							(mid 0.402042 0.402042)
							(end 0.4318 0.3302)
						)
						(arc
							(start 0.4318 -0.3302)
							(mid 0.402042 -0.402042)
							(end 0.3302 -0.4318)
						)
					)
					(width 0)
					(fill yes)
				)
			)
		)
	)
	(footprint ""
		(layer "F.Cu")
		(at 150.495 -275.463 180)
		(property "Reference" "C88"
			(at 0 0 180)
			(layer "F.SilkS")
			(hide yes)
			(effects
				(font
					(size 1.27 1.27)
				)
			)
		)
		(property "Value" "SC1U25V3KX-GP"
			(at 0 -2.8194 180)
			(unlocked yes)
			(layer "F.Fab")
			(hide yes)
			(effects
				(font
					(size 1.016 1.016)
					(thickness 0.1524)
				)
			)
		)
		(property "Device Type" "C603H36"
			(at 0 -4.3434 180)
			(unlocked yes)
			(layer "F.Fab")
			(hide yes)
			(effects
				(font
					(size 1.016 1.016)
					(thickness 0.1524)
				)
			)
		)
		(duplicate_pad_numbers_are_jumpers no)
		(fp_line
			(start 0.508 0)
			(end -0.508 0)
			(stroke
				(width 0.2032)
				(type default)
			)
			(layer "F.SilkS")
		)
		(fp_rect
			(start -0.5842 1.3335)
			(end 0.5842 -1.3335)
			(stroke
				(width 0)
				(type default)
			)
			(fill no)
			(layer "F.CrtYd")
		)
		(fp_rect
			(start -0.5842 1.3335)
			(end 0.5842 -1.3335)
			(stroke
				(width 0)
				(type default)
			)
			(fill no)
			(layer "F.Fab")
		)
		(pad "1" smd custom
			(at 0 -0.762 180)
			(size 0.2159 0.2159)
			(layers "F.Cu" "F.Mask" "F.Paste")
			(net "P12V_HDD4")
			(options
				(clearance outline)
				(anchor circle)
			)
			(primitives
				(gr_poly
					(pts
						(arc
							(start -0.3302 -0.4318)
							(mid -0.402042 -0.402042)
							(end -0.4318 -0.3302)
						)
						(arc
							(start -0.4318 0.3302)
							(mid -0.402042 0.402042)
							(end -0.3302 0.4318)
						)
						(arc
							(start 0.3302 0.4318)
							(mid 0.402042 0.402042)
							(end 0.4318 0.3302)
						)
						(arc
							(start 0.4318 -0.3302)
							(mid 0.402042 -0.402042)
							(end 0.3302 -0.4318)
						)
					)
					(width 0)
					(fill yes)
				)
			)
		)
		(pad "2" smd custom
			(at 0 0.762 180)
			(size 0.2159 0.2159)
			(layers "F.Cu" "F.Mask" "F.Paste")
			(net "GND")
			(options
				(clearance outline)
				(anchor circle)
			)
			(primitives
				(gr_poly
					(pts
						(arc
							(start -0.3302 -0.4318)
							(mid -0.402042 -0.402042)
							(end -0.4318 -0.3302)
						)
						(arc
							(start -0.4318 0.3302)
							(mid -0.402042 0.402042)
							(end -0.3302 0.4318)
						)
						(arc
							(start 0.3302 0.4318)
							(mid 0.402042 0.402042)
							(end 0.4318 0.3302)
						)
						(arc
							(start 0.4318 -0.3302)
							(mid 0.402042 -0.402042)
							(end 0.3302 -0.4318)
						)
					)
					(width 0)
					(fill yes)
				)
			)
		)
	)
	(footprint ""
		(layer "F.Cu")
		(at 66.7258 -263.144 -90)
		(property "Reference" "R174"
			(at 0 0 270)
			(layer "F.SilkS")
			(hide yes)
			(effects
				(font
					(size 1.27 1.27)
				)
			)
		)
		(property "Value" "10KR2F-2-GP"
			(at 0.064008 -3.993896 270)
			(unlocked yes)
			(layer "F.Fab")
			(hide yes)
			(effects
				(font
					(size 1.016 1.016)
					(thickness 0.1524)
				)
			)
		)
		(property "Device Type" "R402H16"
			(at 0.064008 -5.517896 270)
			(unlocked yes)
			(layer "F.Fab")
			(hide yes)
			(effects
				(font
					(size 1.016 1.016)
					(thickness 0.1524)
				)
			)
		)
		(duplicate_pad_numbers_are_jumpers no)
		(fp_line
			(start -0.508 -0.9398)
			(end -0.508 0.9398)
			(stroke
				(width 0.1524)
				(type default)
			)
			(layer "F.SilkS")
		)
		(fp_line
			(start 0.508 -0.9398)
			(end -0.508 -0.9398)
			(stroke
				(width 0.1524)
				(type default)
			)
			(layer "F.SilkS")
		)
		(fp_rect
			(start -0.508 0.9398)
			(end 0.508 -0.9398)
			(stroke
				(width 0)
				(type default)
			)
			(fill no)
			(layer "F.CrtYd")
		)
		(fp_rect
			(start -0.508 0.9398)
			(end 0.508 -0.9398)
			(stroke
				(width 0)
				(type default)
			)
			(fill no)
			(layer "F.Fab")
		)
		(pad "1" smd custom
			(at 0 -0.4445 270)
			(size 0.1397 0.1397)
			(layers "F.Cu" "F.Mask" "F.Paste")
			(net "P3V3_STBY_B")
			(options
				(clearance outline)
				(anchor circle)
			)
			(primitives
				(gr_poly
					(pts
						(arc
							(start -0.1778 -0.2794)
							(mid -0.249642 -0.249642)
							(end -0.2794 -0.1778)
						)
						(arc
							(start -0.2794 0.1778)
							(mid -0.249642 0.249642)
							(end -0.1778 0.2794)
						)
						(arc
							(start 0.1778 0.2794)
							(mid 0.249642 0.249642)
							(end 0.2794 0.1778)
						)
						(arc
							(start 0.2794 -0.1778)
							(mid 0.249642 -0.249642)
							(end 0.1778 -0.2794)
						)
					)
					(width 0)
					(fill yes)
				)
			)
		)
		(pad "2" smd custom
			(at 0 0.4445 270)
			(size 0.1397 0.1397)
			(layers "F.Cu" "F.Mask" "F.Paste")
			(net "HDD_PRSNT_1")
			(options
				(clearance outline)
				(anchor circle)
			)
			(primitives
				(gr_poly
					(pts
						(arc
							(start -0.1778 -0.2794)
							(mid -0.249642 -0.249642)
							(end -0.2794 -0.1778)
						)
						(arc
							(start -0.2794 0.1778)
							(mid -0.249642 0.249642)
							(end -0.1778 0.2794)
						)
						(arc
							(start 0.1778 0.2794)
							(mid 0.249642 0.249642)
							(end 0.2794 0.1778)
						)
						(arc
							(start 0.2794 -0.1778)
							(mid 0.249642 -0.249642)
							(end 0.1778 -0.2794)
						)
					)
					(width 0)
					(fill yes)
				)
			)
		)
	)
	(footprint ""
		(layer "F.Cu")
		(at 312.443876 -217.413586 -90)
		(property "Reference" "R242"
			(at 0 0 270)
			(layer "F.SilkS")
			(hide yes)
			(effects
				(font
					(size 1.27 1.27)
				)
			)
		)
		(property "Value" "4K7R2F-GP"
			(at 0.064008 -3.993896 270)
			(unlocked yes)
			(layer "F.Fab")
			(hide yes)
			(effects
				(font
					(size 1.016 1.016)
					(thickness 0.1524)
				)
			)
		)
		(property "Device Type" "R402H16"
			(at 0.064008 -5.517896 270)
			(unlocked yes)
			(layer "F.Fab")
			(hide yes)
			(effects
				(font
					(size 1.016 1.016)
					(thickness 0.1524)
				)
			)
		)
		(duplicate_pad_numbers_are_jumpers no)
		(fp_line
			(start -0.508 -0.9398)
			(end -0.508 0.9398)
			(stroke
				(width 0.1524)
				(type default)
			)
			(layer "F.SilkS")
		)
		(fp_line
			(start 0.508 -0.9398)
			(end -0.508 -0.9398)
			(stroke
				(width 0.1524)
				(type default)
			)
			(layer "F.SilkS")
		)
		(fp_rect
			(start -0.508 0.9398)
			(end 0.508 -0.9398)
			(stroke
				(width 0)
				(type default)
			)
			(fill no)
			(layer "F.CrtYd")
		)
		(fp_rect
			(start -0.508 0.9398)
			(end 0.508 -0.9398)
			(stroke
				(width 0)
				(type default)
			)
			(fill no)
			(layer "F.Fab")
		)
		(pad "1" smd custom
			(at 0 -0.4445 270)
			(size 0.1397 0.1397)
			(layers "F.Cu" "F.Mask" "F.Paste")
			(net "DRIVE_B_6_FLT_LED")
			(options
				(clearance outline)
				(anchor circle)
			)
			(primitives
				(gr_poly
					(pts
						(arc
							(start -0.1778 -0.2794)
							(mid -0.249642 -0.249642)
							(end -0.2794 -0.1778)
						)
						(arc
							(start -0.2794 0.1778)
							(mid -0.249642 0.249642)
							(end -0.1778 0.2794)
						)
						(arc
							(start 0.1778 0.2794)
							(mid 0.249642 0.249642)
							(end 0.2794 0.1778)
						)
						(arc
							(start 0.2794 -0.1778)
							(mid 0.249642 -0.249642)
							(end 0.1778 -0.2794)
						)
					)
					(width 0)
					(fill yes)
				)
			)
		)
		(pad "2" smd custom
			(at 0 0.4445 270)
			(size 0.1397 0.1397)
			(layers "F.Cu" "F.Mask" "F.Paste")
			(net "GND")
			(options
				(clearance outline)
				(anchor circle)
			)
			(primitives
				(gr_poly
					(pts
						(arc
							(start -0.1778 -0.2794)
							(mid -0.249642 -0.249642)
							(end -0.2794 -0.1778)
						)
						(arc
							(start -0.2794 0.1778)
							(mid -0.249642 0.249642)
							(end -0.1778 0.2794)
						)
						(arc
							(start 0.1778 0.2794)
							(mid 0.249642 0.249642)
							(end 0.2794 0.1778)
						)
						(arc
							(start 0.2794 -0.1778)
							(mid 0.249642 -0.249642)
							(end 0.1778 -0.2794)
						)
					)
					(width 0)
					(fill yes)
				)
			)
		)
	)
	(footprint ""
		(layer "F.Cu")
		(at 395.478 -36.83 180)
		(property "Reference" "C447"
			(at 0 0 180)
			(layer "F.SilkS")
			(hide yes)
			(effects
				(font
					(size 1.27 1.27)
				)
			)
		)
		(property "Value" "SC10U16V6KX-2GP"
			(at -0.0762 -5.1308 180)
			(unlocked yes)
			(layer "F.Fab")
			(hide yes)
			(effects
				(font
					(size 1.016 1.016)
					(thickness 0.1524)
				)
			)
		)
		(property "Device Type" "C1206H71"
			(at -0.127 -6.6548 180)
			(unlocked yes)
			(layer "F.Fab")
			(hide yes)
			(effects
				(font
					(size 1.016 1.016)
					(thickness 0.1524)
				)
			)
		)
		(duplicate_pad_numbers_are_jumpers no)
		(fp_line
			(start 1.016 2.2352)
			(end -1.016 2.2352)
			(stroke
				(width 0.1524)
				(type default)
			)
			(layer "F.SilkS")
		)
		(fp_line
			(start 1.016 0.8382)
			(end 1.016 2.2352)
			(stroke
				(width 0.1524)
				(type default)
			)
			(layer "F.SilkS")
		)
		(fp_line
			(start 1.016 -2.2352)
			(end 1.016 -0.8382)
			(stroke
				(width 0.1524)
				(type default)
			)
			(layer "F.SilkS")
		)
		(fp_line
			(start -1.016 2.2352)
			(end -1.016 0.8382)
			(stroke
				(width 0.1524)
				(type default)
			)
			(layer "F.SilkS")
		)
		(fp_line
			(start -1.016 -0.8382)
			(end -1.016 -2.2352)
			(stroke
				(width 0.1524)
				(type default)
			)
			(layer "F.SilkS")
		)
		(fp_line
			(start -1.016 -2.2352)
			(end 1.016 -2.2352)
			(stroke
				(width 0.1524)
				(type default)
			)
			(layer "F.SilkS")
		)
		(fp_rect
			(start -1.0922 2.3114)
			(end 1.0922 -2.3114)
			(stroke
				(width 0)
				(type default)
			)
			(fill no)
			(layer "F.CrtYd")
		)
		(fp_poly
			(pts
				(xy 1.0922 -2.3114) (xy 1.0922 2.3114) (xy -1.0922 2.3114) (xy -1.0922 -2.3114)
			)
			(stroke
				(width 0)
				(type default)
			)
			(fill no)
			(layer "F.Fab")
		)
		(pad "1" smd rect
			(at 0 -1.397 180)
			(size 1.651 1.27)
			(layers "F.Cu" "F.Mask" "F.Paste")
			(net "P5V_HDD32")
		)
		(pad "2" smd rect
			(at 0 1.397 180)
			(size 1.651 1.27)
			(layers "F.Cu" "F.Mask" "F.Paste")
			(net "GND")
		)
	)
)
